# T6G (Grand Teton) — schematic netlist excerpt (pin names and nets, part order shuffled) for the footprints in the layout excerpt that follows; sources: Cadence DE-HDL packaged netlist, KiCad conversion of 04192023_DAF0TMB3IC0_F0TG_MB_C_brd_V02_OCP.brd

C5001  Q_CAP  1000PF 50V 5% X7R  pkg 0402  page 209 : A = FM_PWRGD_PVDD18_S5_P0 ; B = GND
C1803  Q_CAP  0.1UF 25V 10% X7R  pkg 0402  page 130 : A = P3V3_AUX ; B = GND

(kicad_pcb
	(version 20260206)
	(generator "pcbnew")
	(generator_version "10.0")
	(general
		(thickness 1.6)
		(legacy_teardrops no)
	)
	(paper "A4")
	(title_block
		(title "04192023_DAF0TMB3IC0_F0TG_MB_C_brd_V02_OCP.brd")
		(comment 1 "Grand Teton / footprints 498-499 of 8354")
	)
	(layers
		(0 "F.Cu" signal "TOP")
		(4 "In1.Cu" signal "GND")
		(6 "In2.Cu" signal "IN1")
		(8 "In3.Cu" signal "GND1")
		(10 "In4.Cu" signal "IN2")
		(12 "In5.Cu" signal "GND2")
		(14 "In6.Cu" signal "IN3")
		(16 "In7.Cu" signal "GND3")
		(18 "In8.Cu" signal "VCC")
		(20 "In9.Cu" signal "VCC1")
		(22 "In10.Cu" signal "GND4")
		(24 "In11.Cu" signal "IN4")
		(26 "In12.Cu" signal "GND5")
		(28 "In13.Cu" signal "IN5")
		(30 "In14.Cu" signal "GND6")
		(32 "In15.Cu" signal "IN6")
		(34 "In16.Cu" signal "GND7")
		(2 "B.Cu" signal "BOTTOM")
		(9 "F.Adhes" user "F.Adhesive")
		(11 "B.Adhes" user "B.Adhesive")
		(13 "F.Paste" user "Package Geometry/Pastemask Top")
		(15 "B.Paste" user "Package Geometry/Pastemask Bottom")
		(5 "F.SilkS" user "Ref Des/Silkscreen Top")
		(7 "B.SilkS" user "Ref Des/Silkscreen Bottom")
		(1 "F.Mask" user "Board Geometry/Soldermask Top")
		(3 "B.Mask" user "Board Geometry/Soldermask Bottom")
		(17 "Dwgs.User" user "User.Drawings")
		(19 "Cmts.User" user "User.Comments")
		(21 "Eco1.User" user "User.Eco1")
		(23 "Eco2.User" user "User.Eco2")
		(25 "Edge.Cuts" user "Board Geometry/Outline")
		(27 "Margin" user)
		(31 "F.CrtYd" user "Package Geometry/Place Bound Top")
		(29 "B.CrtYd" user "Package Geometry/Place Bound Bottom")
		(35 "F.Fab" user "Ref Des/Assembly Top")
		(33 "B.Fab" user "Ref Des/Assembly Bottom")
	)
	(footprint ""
		(layer "F.Cu")
		(at 359.059988 -416.392868 90)
		(property "Reference" "C1803"
			(at 0 0 90)
			(layer "F.SilkS")
			(hide yes)
			(effects
				(font
					(size 1.27 1.27)
				)
			)
		)
		(property "Value" ""
			(at 0 0 90)
			(layer "F.Fab")
			(effects
				(font
					(size 1.27 1.27)
				)
			)
		)
		(duplicate_pad_numbers_are_jumpers no)
		(fp_line
			(start 0.7874 -0.4064)
			(end 0.7874 0.4064)
			(stroke
				(width 0.1524)
				(type default)
			)
			(layer "F.SilkS")
		)
		(fp_line
			(start -0.7874 -0.4064)
			(end 0.7874 -0.4064)
			(stroke
				(width 0.1524)
				(type default)
			)
			(layer "F.SilkS")
		)
		(fp_line
			(start 0.7874 0.4064)
			(end -0.7874 0.4064)
			(stroke
				(width 0.1524)
				(type default)
			)
			(layer "F.SilkS")
		)
		(fp_line
			(start -0.7874 0.4064)
			(end -0.7874 -0.4064)
			(stroke
				(width 0.1524)
				(type default)
			)
			(layer "F.SilkS")
		)
		(fp_line
			(start -0.12065 -0.305054)
			(end -0.12065 -0.2794)
			(stroke
				(width 0.1)
				(type default)
			)
			(layer "F.Fab")
		)
		(fp_line
			(start -0.67945 -0.305054)
			(end -0.12065 -0.305054)
			(stroke
				(width 0.1)
				(type default)
			)
			(layer "F.Fab")
		)
		(fp_line
			(start 0.67945 -0.3048)
			(end 0.67945 0.3048)
			(stroke
				(width 0.1)
				(type default)
			)
			(layer "F.Fab")
		)
		(fp_line
			(start 0.12065 -0.3048)
			(end 0.67945 -0.3048)
			(stroke
				(width 0.1)
				(type default)
			)
			(layer "F.Fab")
		)
		(fp_line
			(start 0.12065 -0.2794)
			(end 0.12065 -0.3048)
			(stroke
				(width 0.1)
				(type default)
			)
			(layer "F.Fab")
		)
		(fp_line
			(start -0.12065 -0.2794)
			(end 0.12065 -0.2794)
			(stroke
				(width 0.1)
				(type default)
			)
			(layer "F.Fab")
		)
		(fp_line
			(start 0.120396 0.2794)
			(end -0.12065 0.2794)
			(stroke
				(width 0.1)
				(type default)
			)
			(layer "F.Fab")
		)
		(fp_line
			(start -0.12065 0.2794)
			(end -0.12065 0.3048)
			(stroke
				(width 0.1)
				(type default)
			)
			(layer "F.Fab")
		)
		(fp_line
			(start 0.67945 0.3048)
			(end 0.120396 0.3048)
			(stroke
				(width 0.1)
				(type default)
			)
			(layer "F.Fab")
		)
		(fp_line
			(start 0.120396 0.3048)
			(end 0.120396 0.2794)
			(stroke
				(width 0.1)
				(type default)
			)
			(layer "F.Fab")
		)
		(fp_line
			(start -0.12065 0.3048)
			(end -0.67945 0.3048)
			(stroke
				(width 0.1)
				(type default)
			)
			(layer "F.Fab")
		)
		(fp_line
			(start -0.67945 0.3048)
			(end -0.67945 -0.305054)
			(stroke
				(width 0.1)
				(type default)
			)
			(layer "F.Fab")
		)
		(pad "1" smd circle
			(at -0.40005 0 90)
			(size 0 0)
			(layers "F.Cu" "F.Mask" "F.Paste")
			(net "P3V3_AUX")
		)
		(pad "2" smd circle
			(at 0.40005 0 90)
			(size 0 0)
			(layers "F.Cu" "F.Mask" "F.Paste")
			(net "GND")
		)
	)
	(footprint ""
		(layer "F.Cu")
		(at 200.952608 -111.593376)
		(property "Reference" "C5001"
			(at 0 0 0)
			(layer "F.SilkS")
			(hide yes)
			(effects
				(font
					(size 1.27 1.27)
				)
			)
		)
		(property "Value" ""
			(at 0 0 0)
			(layer "F.Fab")
			(effects
				(font
					(size 1.27 1.27)
				)
			)
		)
		(duplicate_pad_numbers_are_jumpers no)
		(fp_line
			(start -0.7874 -0.4064)
			(end 0.7874 -0.4064)
			(stroke
				(width 0.1524)
				(type default)
			)
			(layer "F.SilkS")
		)
		(fp_line
			(start -0.7874 0.4064)
			(end -0.7874 -0.4064)
			(stroke
				(width 0.1524)
				(type default)
			)
			(layer "F.SilkS")
		)
		(fp_line
			(start 0.7874 -0.4064)
			(end 0.7874 0.4064)
			(stroke
				(width 0.1524)
				(type default)
			)
			(layer "F.SilkS")
		)
		(fp_line
			(start 0.7874 0.4064)
			(end -0.7874 0.4064)
			(stroke
				(width 0.1524)
				(type default)
			)
			(layer "F.SilkS")
		)
		(fp_line
			(start -0.67945 -0.305054)
			(end -0.12065 -0.305054)
			(stroke
				(width 0.1)
				(type default)
			)
			(layer "F.Fab")
		)
		(fp_line
			(start -0.67945 0.3048)
			(end -0.67945 -0.305054)
			(stroke
				(width 0.1)
				(type default)
			)
			(layer "F.Fab")
		)
		(fp_line
			(start -0.12065 -0.305054)
			(end -0.12065 -0.2794)
			(stroke
				(width 0.1)
				(type default)
			)
			(layer "F.Fab")
		)
		(fp_line
			(start -0.12065 -0.2794)
			(end 0.12065 -0.2794)
			(stroke
				(width 0.1)
				(type default)
			)
			(layer "F.Fab")
		)
		(fp_line
			(start -0.12065 0.2794)
			(end -0.12065 0.3048)
			(stroke
				(width 0.1)
				(type default)
			)
			(layer "F.Fab")
		)
		(fp_line
			(start -0.12065 0.3048)
			(end -0.67945 0.3048)
			(stroke
				(width 0.1)
				(type default)
			)
			(layer "F.Fab")
		)
		(fp_line
			(start 0.120396 0.2794)
			(end -0.12065 0.2794)
			(stroke
				(width 0.1)
				(type default)
			)
			(layer "F.Fab")
		)
		(fp_line
			(start 0.120396 0.3048)
			(end 0.120396 0.2794)
			(stroke
				(width 0.1)
				(type default)
			)
			(layer "F.Fab")
		)
		(fp_line
			(start 0.12065 -0.3048)
			(end 0.67945 -0.3048)
			(stroke
				(width 0.1)
				(type default)
			)
			(layer "F.Fab")
		)
		(fp_line
			(start 0.12065 -0.2794)
			(end 0.12065 -0.3048)
			(stroke
				(width 0.1)
				(type default)
			)
			(layer "F.Fab")
		)
		(fp_line
			(start 0.67945 -0.3048)
			(end 0.67945 0.3048)
			(stroke
				(width 0.1)
				(type default)
			)
			(layer "F.Fab")
		)
		(fp_line
			(start 0.67945 0.3048)
			(end 0.120396 0.3048)
			(stroke
				(width 0.1)
				(type default)
			)
			(layer "F.Fab")
		)
		(pad "1" smd circle
			(at -0.40005 0)
			(size 0 0)
			(layers "F.Cu" "F.Mask" "F.Paste")
			(net "FM_PWRGD_PVDD18_S5_P0")
		)
		(pad "2" smd circle
			(at 0.40005 0)
			(size 0 0)
			(layers "F.Cu" "F.Mask" "F.Paste")
			(net "GND")
		)
	)
)
